(kicad_pcb
	(version 20260206)
	(generator "pcbnew")
	(generator_version "10.0")
	(general
		(thickness 1.6)
		(legacy_teardrops no)
	)
	(paper "A4")
	(title_block
		(title "panther-plus-userver — 13130-1b_20150205.brd")
		(comment 1 "Honey Badger (Wiwynn) / footprints 1169-1177 of 1509")
	)
	(layers
		(0 "F.Cu" signal "TOP")
		(4 "In1.Cu" signal "L2")
		(6 "In2.Cu" signal "L3")
		(8 "In3.Cu" signal "L4")
		(10 "In4.Cu" signal "L5")
		(12 "In5.Cu" signal "L6")
		(14 "In6.Cu" signal "L7")
		(16 "In7.Cu" signal "L8")
		(18 "In8.Cu" signal "L9")
		(20 "In9.Cu" signal "L10")
		(22 "In10.Cu" signal "L11")
		(2 "B.Cu" signal "BOTTOM")
		(9 "F.Adhes" user "F.Adhesive")
		(11 "B.Adhes" user "B.Adhesive")
		(13 "F.Paste" user "Package Geometry/Pastemask Top")
		(15 "B.Paste" user "Package Geometry/Pastemask Bottom")
		(5 "F.SilkS" user "Ref Des/Silkscreen Top")
		(7 "B.SilkS" user "Ref Des/Silkscreen Bottom")
		(1 "F.Mask" user "Board Geometry/Soldermask Top")
		(3 "B.Mask" user "Board Geometry/Soldermask Bottom")
		(17 "Dwgs.User" user "User.Drawings")
		(19 "Cmts.User" user "User.Comments")
		(21 "Eco1.User" user "User.Eco1")
		(23 "Eco2.User" user "User.Eco2")
		(25 "Edge.Cuts" user "Board Geometry/Outline")
		(27 "Margin" user)
		(31 "F.CrtYd" user "Package Geometry/Place Bound Top")
		(29 "B.CrtYd" user "Package Geometry/Place Bound Bottom")
		(35 "F.Fab" user "Ref Des/Assembly Top")
		(33 "B.Fab" user "Ref Des/Assembly Bottom")
	)
	(footprint ""
		(layer "B.Cu")
		(at 18.796 -23.241 -90)
		(property "Reference" "PC64"
			(at 0 0 90)
			(layer "B.SilkS")
			(hide yes)
			(effects
				(font
					(size 1.27 1.27)
				)
				(justify mirror)
			)
		)
		(property "Value" "SC1KP50V2KX-1GP"
			(at -1.8923 -1.2065 270)
			(unlocked yes)
			(layer "B.Fab")
			(hide yes)
			(effects
				(font
					(size 1.016 1.016)
					(thickness 0.1524)
				)
				(justify mirror)
			)
		)
		(property "Device Type" "C402H22"
			(at -1.8923 -2.7305 270)
			(unlocked yes)
			(layer "B.Fab")
			(hide yes)
			(effects
				(font
					(size 1.016 1.016)
					(thickness 0.1524)
				)
				(justify mirror)
			)
		)
		(duplicate_pad_numbers_are_jumpers no)
		(fp_rect
			(start 0.381 0.7366)
			(end -0.381 -0.7366)
			(stroke
				(width 0)
				(type default)
			)
			(fill no)
			(layer "B.CrtYd")
		)
		(fp_rect
			(start 0.381 0.7366)
			(end -0.381 -0.7366)
			(stroke
				(width 0)
				(type default)
			)
			(fill no)
			(layer "B.Fab")
		)
		(pad "1" smd custom
			(at 0 -0.4572 90)
			(size 0.1143 0.1143)
			(layers "B.Cu" "B.Mask" "B.Paste")
			(net "AGND_P1V0")
			(options
				(clearance outline)
				(anchor circle)
			)
			(primitives
				(gr_poly
					(pts
						(arc
							(start -0.254 0.1778)
							(mid -0.239121 0.213721)
							(end -0.2032 0.2286)
						)
						(arc
							(start 0.2032 0.2286)
							(mid 0.239121 0.213721)
							(end 0.254 0.1778)
						)
						(arc
							(start 0.254 -0.1778)
							(mid 0.239121 -0.213721)
							(end 0.2032 -0.2286)
						)
						(arc
							(start -0.2032 -0.2286)
							(mid -0.239121 -0.213721)
							(end -0.254 -0.1778)
						)
					)
					(width 0)
					(fill yes)
				)
			)
		)
		(pad "2" smd custom
			(at 0 0.4572 90)
			(size 0.1143 0.1143)
			(layers "B.Cu" "B.Mask" "B.Paste")
			(net "P1V0_ROVP")
			(options
				(clearance outline)
				(anchor circle)
			)
			(primitives
				(gr_poly
					(pts
						(arc
							(start -0.254 0.1778)
							(mid -0.239121 0.213721)
							(end -0.2032 0.2286)
						)
						(arc
							(start 0.2032 0.2286)
							(mid 0.239121 0.213721)
							(end 0.254 0.1778)
						)
						(arc
							(start 0.254 -0.1778)
							(mid 0.239121 -0.213721)
							(end 0.2032 -0.2286)
						)
						(arc
							(start -0.2032 -0.2286)
							(mid -0.239121 -0.213721)
							(end -0.254 -0.1778)
						)
					)
					(width 0)
					(fill yes)
				)
			)
		)
	)
	(footprint ""
		(layer "B.Cu")
		(at 94.1578 -41.91 -90)
		(property "Reference" "TP23"
			(at 0 0 90)
			(layer "B.SilkS")
			(hide yes)
			(effects
				(font
					(size 1.27 1.27)
				)
				(justify mirror)
			)
		)
		(property "Value" "TPAD24"
			(at 0 -2.9972 270)
			(unlocked yes)
			(layer "B.Fab")
			(hide yes)
			(effects
				(font
					(size 1.016 1.016)
					(thickness 0.1524)
				)
				(justify mirror)
			)
		)
		(property "Device Type" "TPAD24"
			(at 0 -4.5212 270)
			(unlocked yes)
			(layer "B.Fab")
			(hide yes)
			(effects
				(font
					(size 1.016 1.016)
					(thickness 0.1524)
				)
				(justify mirror)
			)
		)
		(duplicate_pad_numbers_are_jumpers no)
		(fp_poly
			(pts
				(arc
					(start 0 -0.3048)
					(mid 0 0.3048)
					(end 0 -0.3048)
				)
			)
			(stroke
				(width 0)
				(type default)
			)
			(fill no)
			(layer "B.CrtYd")
		)
		(fp_poly
			(pts
				(arc
					(start 0 -0.6096)
					(mid 0 0.6096)
					(end 0 -0.6096)
				)
			)
			(stroke
				(width 0)
				(type default)
			)
			(fill no)
			(layer "B.Fab")
		)
		(pad "1" smd circle
			(at 0 0 90)
			(size 0.6096 0.6096)
			(layers "B.Cu" "B.Mask" "B.Paste")
			(net "TP_CPU_RSVD2")
		)
	)
	(footprint ""
		(layer "B.Cu")
		(at 94.740984 -17.288002 90)
		(property "Reference" "L9"
			(at 0 0 90)
			(layer "B.SilkS")
			(hide yes)
			(effects
				(font
					(size 1.27 1.27)
				)
				(justify mirror)
			)
		)
		(property "Value" "BLM18PG121SN1D-GP"
			(at 0.0254 -2.8956 90)
			(unlocked yes)
			(layer "B.Fab")
			(hide yes)
			(effects
				(font
					(size 1.016 1.016)
					(thickness 0.1524)
				)
				(justify mirror)
			)
		)
		(property "Device Type" "L1608-UH38"
			(at 0.0254 -4.4196 90)
			(unlocked yes)
			(layer "B.Fab")
			(hide yes)
			(effects
				(font
					(size 1.016 1.016)
					(thickness 0.1524)
				)
				(justify mirror)
			)
		)
		(duplicate_pad_numbers_are_jumpers no)
		(fp_line
			(start 0.4064 0)
			(end -0.4064 0)
			(stroke
				(width 0.2032)
				(type default)
			)
			(layer "B.SilkS")
		)
		(fp_rect
			(start 0.635 1.1811)
			(end -0.635 -1.1811)
			(stroke
				(width 0)
				(type default)
			)
			(fill no)
			(layer "B.CrtYd")
		)
		(fp_rect
			(start 0.635 1.1811)
			(end -0.635 -1.1811)
			(stroke
				(width 0)
				(type default)
			)
			(fill no)
			(layer "B.Fab")
		)
		(pad "1" smd custom
			(at 0 -0.6604 270)
			(size 0.19685 0.19685)
			(layers "B.Cu" "B.Mask" "B.Paste")
			(net "P1V0")
			(options
				(clearance outline)
				(anchor circle)
			)
			(primitives
				(gr_poly
					(pts
						(arc
							(start 0.508 0.2921)
							(mid 0.478242 0.363942)
							(end 0.4064 0.3937)
						)
						(arc
							(start -0.4064 0.3937)
							(mid -0.478242 0.363942)
							(end -0.508 0.2921)
						)
						(arc
							(start -0.508 -0.2921)
							(mid -0.478242 -0.363942)
							(end -0.4064 -0.3937)
						)
						(arc
							(start 0.4064 -0.3937)
							(mid 0.478242 -0.363942)
							(end 0.508 -0.2921)
						)
					)
					(width 0)
					(fill yes)
				)
			)
		)
		(pad "2" smd custom
			(at 0 0.6604 270)
			(size 0.19685 0.19685)
			(layers "B.Cu" "B.Mask" "B.Paste")
			(net "VCCACKDDR1")
			(options
				(clearance outline)
				(anchor circle)
			)
			(primitives
				(gr_poly
					(pts
						(arc
							(start 0.508 0.2921)
							(mid 0.478242 0.363942)
							(end 0.4064 0.3937)
						)
						(arc
							(start -0.4064 0.3937)
							(mid -0.478242 0.363942)
							(end -0.508 0.2921)
						)
						(arc
							(start -0.508 -0.2921)
							(mid -0.478242 -0.363942)
							(end -0.4064 -0.3937)
						)
						(arc
							(start 0.4064 -0.3937)
							(mid 0.478242 -0.363942)
							(end 0.508 -0.2921)
						)
					)
					(width 0)
					(fill yes)
				)
			)
		)
	)
	(footprint ""
		(layer "B.Cu")
		(at 102.489 -51.451002 180)
		(property "Reference" "C129"
			(at 0 0 0)
			(layer "B.SilkS")
			(hide yes)
			(effects
				(font
					(size 1.27 1.27)
				)
				(justify mirror)
			)
		)
		(property "Value" "SC1U10V2KX-1GP"
			(at -1.1811 -2.7051 180)
			(unlocked yes)
			(layer "B.Fab")
			(hide yes)
			(effects
				(font
					(size 1.016 1.016)
					(thickness 0.1524)
				)
				(justify mirror)
			)
		)
		(property "Device Type" "C402H22"
			(at -1.1811 -4.2291 180)
			(unlocked yes)
			(layer "B.Fab")
			(hide yes)
			(effects
				(font
					(size 1.016 1.016)
					(thickness 0.1524)
				)
				(justify mirror)
			)
		)
		(duplicate_pad_numbers_are_jumpers no)
		(fp_rect
			(start 0.381 0.7366)
			(end -0.381 -0.7366)
			(stroke
				(width 0)
				(type default)
			)
			(fill no)
			(layer "B.CrtYd")
		)
		(fp_rect
			(start 0.381 0.7366)
			(end -0.381 -0.7366)
			(stroke
				(width 0)
				(type default)
			)
			(fill no)
			(layer "B.Fab")
		)
		(pad "1" smd custom
			(at 0 -0.4572)
			(size 0.1143 0.1143)
			(layers "B.Cu" "B.Mask" "B.Paste")
			(net "PV_VDDR")
			(options
				(clearance outline)
				(anchor circle)
			)
			(primitives
				(gr_poly
					(pts
						(arc
							(start -0.254 0.1778)
							(mid -0.239121 0.213721)
							(end -0.2032 0.2286)
						)
						(arc
							(start 0.2032 0.2286)
							(mid 0.239121 0.213721)
							(end 0.254 0.1778)
						)
						(arc
							(start 0.254 -0.1778)
							(mid 0.239121 -0.213721)
							(end 0.2032 -0.2286)
						)
						(arc
							(start -0.2032 -0.2286)
							(mid -0.239121 -0.213721)
							(end -0.254 -0.1778)
						)
					)
					(width 0)
					(fill yes)
				)
			)
		)
		(pad "2" smd custom
			(at 0 0.4572)
			(size 0.1143 0.1143)
			(layers "B.Cu" "B.Mask" "B.Paste")
			(net "GND")
			(options
				(clearance outline)
				(anchor circle)
			)
			(primitives
				(gr_poly
					(pts
						(arc
							(start -0.254 0.1778)
							(mid -0.239121 0.213721)
							(end -0.2032 0.2286)
						)
						(arc
							(start 0.2032 0.2286)
							(mid 0.239121 0.213721)
							(end 0.254 0.1778)
						)
						(arc
							(start 0.254 -0.1778)
							(mid 0.239121 -0.213721)
							(end 0.2032 -0.2286)
						)
						(arc
							(start -0.2032 -0.2286)
							(mid -0.239121 -0.213721)
							(end -0.254 -0.1778)
						)
					)
					(width 0)
					(fill yes)
				)
			)
		)
	)
	(footprint ""
		(layer "B.Cu")
		(at 60.833 -13.335 180)
		(property "Reference" "R382"
			(at 0 0 0)
			(layer "B.SilkS")
			(hide yes)
			(effects
				(font
					(size 1.27 1.27)
				)
				(justify mirror)
			)
		)
		(property "Value" "0R2J-2-GP"
			(at -0.064008 -3.993896 180)
			(unlocked yes)
			(layer "B.Fab")
			(hide yes)
			(effects
				(font
					(size 1.016 1.016)
					(thickness 0.1524)
				)
				(justify mirror)
			)
		)
		(property "Device Type" "R402H16"
			(at -0.064008 -5.517896 180)
			(unlocked yes)
			(layer "B.Fab")
			(hide yes)
			(effects
				(font
					(size 1.016 1.016)
					(thickness 0.1524)
				)
				(justify mirror)
			)
		)
		(duplicate_pad_numbers_are_jumpers no)
		(fp_rect
			(start 0.381 0.8382)
			(end -0.381 -0.8382)
			(stroke
				(width 0)
				(type default)
			)
			(fill no)
			(layer "B.CrtYd")
		)
		(fp_rect
			(start 0.381 0.8382)
			(end -0.381 -0.8382)
			(stroke
				(width 0)
				(type default)
			)
			(fill no)
			(layer "B.Fab")
		)
		(pad "1" smd custom
			(at 0 -0.4318)
			(size 0.127 0.127)
			(layers "B.Cu" "B.Mask" "B.Paste")
			(net "PCIE1_RESET#")
			(options
				(clearance outline)
				(anchor circle)
			)
			(primitives
				(gr_poly
					(pts
						(arc
							(start -0.2032 0.2794)
							(mid -0.239121 0.264521)
							(end -0.254 0.2286)
						)
						(arc
							(start -0.254 -0.2286)
							(mid -0.239121 -0.264521)
							(end -0.2032 -0.2794)
						)
						(arc
							(start 0.2032 -0.2794)
							(mid 0.239121 -0.264521)
							(end 0.254 -0.2286)
						)
						(arc
							(start 0.254 0.2286)
							(mid 0.239121 0.264521)
							(end 0.2032 0.2794)
						)
					)
					(width 0)
					(fill yes)
				)
			)
		)
		(pad "2" smd custom
			(at 0 0.4318)
			(size 0.127 0.127)
			(layers "B.Cu" "B.Mask" "B.Paste")
			(net "PMU_BUF_PLTRST#")
			(options
				(clearance outline)
				(anchor circle)
			)
			(primitives
				(gr_poly
					(pts
						(arc
							(start -0.2032 0.2794)
							(mid -0.239121 0.264521)
							(end -0.254 0.2286)
						)
						(arc
							(start -0.254 -0.2286)
							(mid -0.239121 -0.264521)
							(end -0.2032 -0.2794)
						)
						(arc
							(start 0.2032 -0.2794)
							(mid 0.239121 -0.264521)
							(end 0.254 -0.2286)
						)
						(arc
							(start 0.254 0.2286)
							(mid 0.239121 0.264521)
							(end 0.2032 0.2794)
						)
					)
					(width 0)
					(fill yes)
				)
			)
		)
	)
	(footprint ""
		(layer "B.Cu")
		(at 86.60384 -38.2016 90)
		(property "Reference" "R331"
			(at 0 0 90)
			(layer "B.SilkS")
			(hide yes)
			(effects
				(font
					(size 1.27 1.27)
				)
				(justify mirror)
			)
		)
		(property "Value" "1MR3F-GP"
			(at 0.0254 -2.5146 90)
			(unlocked yes)
			(layer "B.Fab")
			(hide yes)
			(effects
				(font
					(size 1.016 1.016)
					(thickness 0.1524)
				)
				(justify mirror)
			)
		)
		(property "Device Type" "R603H22"
			(at 0.0254 -4.0386 90)
			(unlocked yes)
			(layer "B.Fab")
			(hide yes)
			(effects
				(font
					(size 1.016 1.016)
					(thickness 0.1524)
				)
				(justify mirror)
			)
		)
		(duplicate_pad_numbers_are_jumpers no)
		(fp_line
			(start 0.2032 0)
			(end 0.4191 0)
			(stroke
				(width 0.2032)
				(type default)
			)
			(layer "B.SilkS")
		)
		(fp_line
			(start -0.4318 0)
			(end -0.2032 0)
			(stroke
				(width 0.2032)
				(type default)
			)
			(layer "B.SilkS")
		)
		(fp_rect
			(start 0.635 1.1811)
			(end -0.635 -1.1811)
			(stroke
				(width 0)
				(type default)
			)
			(fill no)
			(layer "B.CrtYd")
		)
		(fp_rect
			(start 0.635 1.1811)
			(end -0.635 -1.1811)
			(stroke
				(width 0)
				(type default)
			)
			(fill no)
			(layer "B.Fab")
		)
		(pad "1" smd custom
			(at 0 -0.6604 270)
			(size 0.19685 0.19685)
			(layers "B.Cu" "B.Mask" "B.Paste")
			(net "PU_INTRUDER#")
			(options
				(clearance outline)
				(anchor circle)
			)
			(primitives
				(gr_poly
					(pts
						(arc
							(start 0.508 0.2921)
							(mid 0.478242 0.363942)
							(end 0.4064 0.3937)
						)
						(arc
							(start -0.4064 0.3937)
							(mid -0.478242 0.363942)
							(end -0.508 0.2921)
						)
						(arc
							(start -0.508 -0.2921)
							(mid -0.478242 -0.363942)
							(end -0.4064 -0.3937)
						)
						(arc
							(start 0.4064 -0.3937)
							(mid 0.478242 -0.363942)
							(end 0.508 -0.2921)
						)
					)
					(width 0)
					(fill yes)
				)
			)
		)
		(pad "2" smd custom
			(at 0 0.6604 270)
			(size 0.19685 0.19685)
			(layers "B.Cu" "B.Mask" "B.Paste")
			(net "P3V3_RTC")
			(options
				(clearance outline)
				(anchor circle)
			)
			(primitives
				(gr_poly
					(pts
						(arc
							(start 0.508 0.2921)
							(mid 0.478242 0.363942)
							(end 0.4064 0.3937)
						)
						(arc
							(start -0.4064 0.3937)
							(mid -0.478242 0.363942)
							(end -0.508 0.2921)
						)
						(arc
							(start -0.508 -0.2921)
							(mid -0.478242 -0.363942)
							(end -0.4064 -0.3937)
						)
						(arc
							(start 0.4064 -0.3937)
							(mid 0.478242 -0.363942)
							(end 0.508 -0.2921)
						)
					)
					(width 0)
					(fill yes)
				)
			)
		)
	)
	(footprint ""
		(layer "B.Cu")
		(at 139.065 -30.353 -90)
		(property "Reference" "R482"
			(at 0 0 90)
			(layer "B.SilkS")
			(hide yes)
			(effects
				(font
					(size 1.27 1.27)
				)
				(justify mirror)
			)
		)
		(property "Value" "0R2J-2-GP"
			(at -1.7907 -1.1176 270)
			(unlocked yes)
			(layer "B.Fab")
			(hide yes)
			(effects
				(font
					(size 1.016 1.016)
					(thickness 0.1524)
				)
				(justify mirror)
			)
		)
		(property "Device Type" "R402H16"
			(at -1.7907 -2.6416 270)
			(unlocked yes)
			(layer "B.Fab")
			(hide yes)
			(effects
				(font
					(size 1.016 1.016)
					(thickness 0.1524)
				)
				(justify mirror)
			)
		)
		(duplicate_pad_numbers_are_jumpers no)
		(fp_rect
			(start 0.381 0.8382)
			(end -0.381 -0.8382)
			(stroke
				(width 0)
				(type default)
			)
			(fill no)
			(layer "B.CrtYd")
		)
		(fp_rect
			(start 0.381 0.8382)
			(end -0.381 -0.8382)
			(stroke
				(width 0)
				(type default)
			)
			(fill no)
			(layer "B.Fab")
		)
		(pad "1" smd custom
			(at 0 -0.4318 90)
			(size 0.127 0.127)
			(layers "B.Cu" "B.Mask" "B.Paste")
			(net "PMU_SLP_S45#")
			(options
				(clearance outline)
				(anchor circle)
			)
			(primitives
				(gr_poly
					(pts
						(arc
							(start -0.2032 0.2794)
							(mid -0.239121 0.264521)
							(end -0.254 0.2286)
						)
						(arc
							(start -0.254 -0.2286)
							(mid -0.239121 -0.264521)
							(end -0.2032 -0.2794)
						)
						(arc
							(start 0.2032 -0.2794)
							(mid 0.239121 -0.264521)
							(end 0.254 -0.2286)
						)
						(arc
							(start 0.254 0.2286)
							(mid 0.239121 0.264521)
							(end 0.2032 0.2794)
						)
					)
					(width 0)
					(fill yes)
				)
			)
		)
		(pad "2" smd custom
			(at 0 0.4318 90)
			(size 0.127 0.127)
			(layers "B.Cu" "B.Mask" "B.Paste")
			(net "PMU_SLP_R_S45#")
			(options
				(clearance outline)
				(anchor circle)
			)
			(primitives
				(gr_poly
					(pts
						(arc
							(start -0.2032 0.2794)
							(mid -0.239121 0.264521)
							(end -0.254 0.2286)
						)
						(arc
							(start -0.254 -0.2286)
							(mid -0.239121 -0.264521)
							(end -0.2032 -0.2794)
						)
						(arc
							(start 0.2032 -0.2794)
							(mid 0.239121 -0.264521)
							(end 0.254 -0.2286)
						)
						(arc
							(start 0.254 0.2286)
							(mid 0.239121 0.264521)
							(end 0.2032 0.2794)
						)
					)
					(width 0)
					(fill yes)
				)
			)
		)
	)
	(footprint ""
		(layer "B.Cu")
		(at 94.4118 -39.73576 -90)
		(property "Reference" "TP31"
			(at 0 0 90)
			(layer "B.SilkS")
			(hide yes)
			(effects
				(font
					(size 1.27 1.27)
				)
				(justify mirror)
			)
		)
		(property "Value" "TPAD24"
			(at 0 -2.9972 270)
			(unlocked yes)
			(layer "B.Fab")
			(hide yes)
			(effects
				(font
					(size 1.016 1.016)
					(thickness 0.1524)
				)
				(justify mirror)
			)
		)
		(property "Device Type" "TPAD24"
			(at 0 -4.5212 270)
			(unlocked yes)
			(layer "B.Fab")
			(hide yes)
			(effects
				(font
					(size 1.016 1.016)
					(thickness 0.1524)
				)
				(justify mirror)
			)
		)
		(duplicate_pad_numbers_are_jumpers no)
		(fp_poly
			(pts
				(arc
					(start 0 -0.3048)
					(mid 0 0.3048)
					(end 0 -0.3048)
				)
			)
			(stroke
				(width 0)
				(type default)
			)
			(fill no)
			(layer "B.CrtYd")
		)
		(fp_poly
			(pts
				(arc
					(start 0 -0.6096)
					(mid 0 0.6096)
					(end 0 -0.6096)
				)
			)
			(stroke
				(width 0)
				(type default)
			)
			(fill no)
			(layer "B.Fab")
		)
		(pad "1" smd circle
			(at 0 0 90)
			(size 0.6096 0.6096)
			(layers "B.Cu" "B.Mask" "B.Paste")
			(net "TP_CPU_RSVD8")
		)
	)
	(footprint ""
		(layer "B.Cu")
		(at 163.322 -72.39 90)
		(property "Reference" "C109"
			(at 0 0 90)
			(layer "B.SilkS")
			(hide yes)
			(effects
				(font
					(size 1.27 1.27)
				)
				(justify mirror)
			)
		)
		(property "Value" "SCD1U16V2KX-3GP"
			(at -1.1811 -2.7051 90)
			(unlocked yes)
			(layer "B.Fab")
			(hide yes)
			(effects
				(font
					(size 1.016 1.016)
					(thickness 0.1524)
				)
				(justify mirror)
			)
		)
		(property "Device Type" "C402H22"
			(at -1.1811 -4.2291 90)
			(unlocked yes)
			(layer "B.Fab")
			(hide yes)
			(effects
				(font
					(size 1.016 1.016)
					(thickness 0.1524)
				)
				(justify mirror)
			)
		)
		(duplicate_pad_numbers_are_jumpers no)
		(fp_rect
			(start 0.381 0.7366)
			(end -0.381 -0.7366)
			(stroke
				(width 0)
				(type default)
			)
			(fill no)
			(layer "B.CrtYd")
		)
		(fp_rect
			(start 0.381 0.7366)
			(end -0.381 -0.7366)
			(stroke
				(width 0)
				(type default)
			)
			(fill no)
			(layer "B.Fab")
		)
		(pad "1" smd custom
			(at 0 -0.4572 270)
			(size 0.1143 0.1143)
			(layers "B.Cu" "B.Mask" "B.Paste")
			(net "DDR3_M_A_VREF_CA")
			(options
				(clearance outline)
				(anchor circle)
			)
			(primitives
				(gr_poly
					(pts
						(arc
							(start -0.254 0.1778)
							(mid -0.239121 0.213721)
							(end -0.2032 0.2286)
						)
						(arc
							(start 0.2032 0.2286)
							(mid 0.239121 0.213721)
							(end 0.254 0.1778)
						)
						(arc
							(start 0.254 -0.1778)
							(mid 0.239121 -0.213721)
							(end 0.2032 -0.2286)
						)
						(arc
							(start -0.2032 -0.2286)
							(mid -0.239121 -0.213721)
							(end -0.254 -0.1778)
						)
					)
					(width 0)
					(fill yes)
				)
			)
		)
		(pad "2" smd custom
			(at 0 0.4572 270)
			(size 0.1143 0.1143)
			(layers "B.Cu" "B.Mask" "B.Paste")
			(net "GND")
			(options
				(clearance outline)
				(anchor circle)
			)
			(primitives
				(gr_poly
					(pts
						(arc
							(start -0.254 0.1778)
							(mid -0.239121 0.213721)
							(end -0.2032 0.2286)
						)
						(arc
							(start 0.2032 0.2286)
							(mid 0.239121 0.213721)
							(end 0.254 0.1778)
						)
						(arc
							(start 0.254 -0.1778)
							(mid 0.239121 -0.213721)
							(end 0.2032 -0.2286)
						)
						(arc
							(start -0.2032 -0.2286)
							(mid -0.239121 -0.213721)
							(end -0.254 -0.1778)
						)
					)
					(width 0)
					(fill yes)
				)
			)
		)
	)
)
